(kicad_pcb
	(version 20241229)
	(generator "pcbnew")
	(generator_version "9.0")
	(general
		(thickness 1.599998)
		(legacy_teardrops no)
	)
	(paper "A4")
	(title_block
		(title "Artix - Datacenter Secure Control Module (DC-SCM)")
		(date "2024-11-06")
		(rev "1.1.3")
		(comment 9 "footprints 103-103 of 544")
	)
	(layers
		(0 "F.Cu" signal)
		(4 "In1.Cu" signal)
		(6 "In2.Cu" signal)
		(8 "In3.Cu" signal)
		(10 "In4.Cu" signal)
		(12 "In5.Cu" signal)
		(14 "In6.Cu" signal)
		(2 "B.Cu" signal)
		(9 "F.Adhes" user "F.Adhesive")
		(11 "B.Adhes" user "B.Adhesive")
		(13 "F.Paste" user)
		(15 "B.Paste" user)
		(5 "F.SilkS" user "F.Silkscreen")
		(7 "B.SilkS" user "B.Silkscreen")
		(1 "F.Mask" user)
		(3 "B.Mask" user)
		(17 "Dwgs.User" user "User.Drawings")
		(19 "Cmts.User" user "User.Comments")
		(21 "Eco1.User" user "User.Eco1")
		(23 "Eco2.User" user "User.Eco2")
		(25 "Edge.Cuts" user)
		(27 "Margin" user)
		(31 "F.CrtYd" user "F.Courtyard")
		(29 "B.CrtYd" user "B.Courtyard")
		(35 "F.Fab" user)
		(33 "B.Fab" user)
	)
	(footprint "antmicro-footprints:QFN-32-1EP_5x5mm"
		(layer "F.Cu")
		(at 125.175 111.375 180)
		(property "Reference" "U17"
			(at -0.925 3.175 180)
			(layer "F.SilkS")
			(effects
				(font
					(size 0.7 0.7)
					(thickness 0.15)
				)
				(justify left bottom)
			)
		)
		(property "Value" "USB3300-EZK-TR"
			(at -4.94 3.91 180)
			(layer "F.Fab")
			(effects
				(font
					(size 0.7 0.7)
					(thickness 0.15)
				)
				(justify left bottom)
			)
		)
		(property "Datasheet" "https://ww1.microchip.com/downloads/en/DeviceDoc/00001783C.pdf"
			(at 0 0 180)
			(layer "F.Fab")
			(hide yes)
			(effects
				(font
					(size 1.27 1.27)
					(thickness 0.15)
				)
			)
		)
		(property "Description" "USB Interface, USB Host Controller, USB 2.0 OTG, 3 V, 3.6 V, VQFN, 32 Pins"
			(at 0 0 180)
			(layer "F.Fab")
			(hide yes)
			(effects
				(font
					(size 1.27 1.27)
					(thickness 0.15)
				)
			)
		)
		(property "Author" "Antmicro"
			(at 250.35 222.75 0)
			(layer "F.Fab")
			(hide yes)
			(effects
				(font
					(size 1 1)
					(thickness 0.15)
				)
			)
		)
		(property "License" "Apache-2.0"
			(at 250.35 222.75 0)
			(layer "F.Fab")
			(hide yes)
			(effects
				(font
					(size 1 1)
					(thickness 0.15)
				)
			)
		)
		(property "MPN" "USB3300-EZK-TR"
			(at 250.35 222.75 0)
			(layer "F.Fab")
			(hide yes)
			(effects
				(font
					(size 1 1)
					(thickness 0.15)
				)
			)
		)
		(property "Manufacturer" "Microchip Technology"
			(at 250.35 222.75 0)
			(layer "F.Fab")
			(hide yes)
			(effects
				(font
					(size 1 1)
					(thickness 0.15)
				)
			)
		)
		(sheetname "/Interfaces/")
		(sheetfile "interfaces.kicad_sch")
		(attr smd)
		(fp_line
			(start 2.581 2.648)
			(end 2.178 2.648)
			(stroke
				(width 0.15)
				(type solid)
			)
			(layer "F.SilkS")
		)
		(fp_line
			(start 2.581 2.249)
			(end 2.581 2.648)
			(stroke
				(width 0.15)
				(type solid)
			)
			(layer "F.SilkS")
		)
		(fp_line
			(start 2.581 -2.551)
			(end 2.581 -2.149)
			(stroke
				(width 0.15)
				(type solid)
			)
			(layer "F.SilkS")
		)
		(fp_line
			(start 2.581 -2.551)
			(end 2.178 -2.551)
			(stroke
				(width 0.15)
				(type solid)
			)
			(layer "F.SilkS")
		)
		(fp_line
			(start -2.221 2.648)
			(end -2.62 2.648)
			(stroke
				(width 0.15)
				(type solid)
			)
			(layer "F.SilkS")
		)
		(fp_line
			(start -2.221 -2.551)
			(end -2.62 -2.149)
			(stroke
				(width 0.15)
				(type solid)
			)
			(layer "F.SilkS")
		)
		(fp_line
			(start -2.62 2.648)
			(end -2.62 2.249)
			(stroke
				(width 0.15)
				(type solid)
			)
			(layer "F.SilkS")
		)
		(fp_circle
			(center -3.25 -1.702)
			(end -3.2 -1.702)
			(stroke
				(width 0.15)
				(type solid)
			)
			(fill yes)
			(layer "F.SilkS")
		)
		(fp_rect
			(start 0.203 1.474)
			(end 1.403 0.274)
			(stroke
				(width 0.2)
				(type solid)
			)
			(fill yes)
			(layer "F.Paste")
		)
		(fp_rect
			(start 0.203 -0.175)
			(end 1.403 -1.375)
			(stroke
				(width 0.2)
				(type solid)
			)
			(fill yes)
			(layer "F.Paste")
		)
		(fp_rect
			(start -1.446 1.474)
			(end -0.246 0.274)
			(stroke
				(width 0.2)
				(type solid)
			)
			(fill yes)
			(layer "F.Paste")
		)
		(fp_rect
			(start -1.446 -0.175)
			(end -0.246 -1.375)
			(stroke
				(width 0.2)
				(type solid)
			)
			(fill yes)
			(layer "F.Paste")
		)
		(fp_rect
			(start -2.74 -2.75)
			(end 2.75 2.74)
			(stroke
				(width 0.05)
				(type solid)
			)
			(fill no)
			(layer "F.CrtYd")
		)
		(fp_line
			(start -2.499 -2.299)
			(end -2.298 -2.5)
			(stroke
				(width 0.15)
				(type solid)
			)
			(layer "F.Fab")
		)
		(fp_rect
			(start -2.499 -2.5)
			(end 2.5 2.499)
			(stroke
				(width 0.15)
				(type solid)
			)
			(fill no)
			(layer "F.Fab")
		)
		(pad "1" smd rect
			(at -2.495 -1.702 90)
			(size 0.28 0.85)
			(layers "F.Cu" "F.Mask" "F.Paste")
			(net 1 "GND")
			(pinfunction "GND")
			(pintype "power_in")
			(solder_mask_margin 0.07)
		)
		(pad "2" smd rect
			(at -2.495 -1.2 90)
			(size 0.28 0.85)
			(layers "F.Cu" "F.Mask" "F.Paste")
			(net 1 "GND")
			(pinfunction "GND")
			(pintype "passive")
			(solder_mask_margin 0.07)
		)
		(pad "3" smd rect
			(at -2.495 -0.701 90)
			(size 0.28 0.85)
			(layers "F.Cu" "F.Mask" "F.Paste")
			(net 647 "unconnected-(U17-CPEN-Pad3)")
			(pinfunction "CPEN")
			(pintype "output+no_connect")
			(solder_mask_margin 0.07)
		)
		(pad "4" smd rect
			(at -2.495 -0.201 90)
			(size 0.28 0.85)
			(layers "F.Cu" "F.Mask" "F.Paste")
			(net 302 "Net-(U17-VBUS)")
			(pinfunction "VBUS")
			(pintype "bidirectional")
			(solder_mask_margin 0.07)
		)
		(pad "5" smd rect
			(at -2.495 0.296 90)
			(size 0.28 0.85)
			(layers "F.Cu" "F.Mask" "F.Paste")
			(net 648 "unconnected-(U17-ID-Pad5)")
			(pinfunction "ID")
			(pintype "input+no_connect")
			(solder_mask_margin 0.07)
		)
		(pad "6" smd rect
			(at -2.495 0.8 90)
			(size 0.28 0.85)
			(layers "F.Cu" "F.Mask" "F.Paste")
			(net 2 "VCC3V3")
			(pinfunction "VDD3.3")
			(pintype "power_in")
			(solder_mask_margin 0.07)
		)
		(pad "7" smd rect
			(at -2.495 1.3 90)
			(size 0.28 0.85)
			(layers "F.Cu" "F.Mask" "F.Paste")
			(net 385 "USB1_D_P")
			(pinfunction "DP")
			(pintype "bidirectional")
			(solder_mask_margin 0.07)
		)
		(pad "8" smd rect
			(at -2.495 1.8 90)
			(size 0.28 0.85)
			(layers "F.Cu" "F.Mask" "F.Paste")
			(net 386 "USB1_D_N")
			(pinfunction "DM")
			(pintype "bidirectional")
			(solder_mask_margin 0.07)
		)
		(pad "9" smd rect
			(at -1.768 2.523 90)
			(size 0.85 0.28)
			(layers "F.Cu" "F.Mask" "F.Paste")
			(net 442 "ULPI1_RESET")
			(pinfunction "RESET")
			(pintype "input")
			(solder_mask_margin 0.07)
		)
		(pad "10" smd rect
			(at -1.269 2.523 90)
			(size 0.85 0.28)
			(layers "F.Cu" "F.Mask" "F.Paste")
			(net 649 "unconnected-(U17-EXTVBUS-Pad10)")
			(pinfunction "EXTVBUS")
			(pintype "input+no_connect")
			(solder_mask_margin 0.07)
		)
		(pad "11" smd rect
			(at -0.772 2.523 90)
			(size 0.85 0.28)
			(layers "F.Cu" "F.Mask" "F.Paste")
			(net 444 "ULPI1_NXT")
			(pinfunction "NXT")
			(pintype "output")
			(solder_mask_margin 0.07)
		)
		(pad "12" smd rect
			(at -0.272 2.523 90)
			(size 0.85 0.28)
			(layers "F.Cu" "F.Mask" "F.Paste")
			(net 445 "ULPI1_DIR")
			(pinfunction "DIR")
			(pintype "output")
			(solder_mask_margin 0.07)
		)
		(pad "13" smd rect
			(at 0.229 2.523 90)
			(size 0.85 0.28)
			(layers "F.Cu" "F.Mask" "F.Paste")
			(net 446 "ULPI1_STP")
			(pinfunction "STP")
			(pintype "input")
			(solder_mask_margin 0.07)
		)
		(pad "14" smd rect
			(at 0.728 2.523 90)
			(size 0.85 0.28)
			(layers "F.Cu" "F.Mask" "F.Paste")
			(net 447 "ULPI1_CLKOUT")
			(pinfunction "CLKOUT")
			(pintype "output")
			(solder_mask_margin 0.07)
		)
		(pad "15" smd rect
			(at 1.23 2.523 90)
			(size 0.85 0.28)
			(layers "F.Cu" "F.Mask" "F.Paste")
			(net 105 "Net-(C20-Pad2)")
			(pinfunction "VDD1.8")
			(pintype "power_in")
			(solder_mask_margin 0.07)
		)
		(pad "16" smd rect
			(at 1.73 2.523 90)
			(size 0.85 0.28)
			(layers "F.Cu" "F.Mask" "F.Paste")
			(net 2 "VCC3V3")
			(pinfunction "VDD3.3")
			(pintype "passive")
			(solder_mask_margin 0.07)
		)
		(pad "17" smd rect
			(at 2.456 1.8 90)
			(size 0.28 0.85)
			(layers "F.Cu" "F.Mask" "F.Paste")
			(net 448 "ULPI1_DATA7")
			(pinfunction "DATA[7]")
			(pintype "bidirectional")
			(solder_mask_margin 0.07)
		)
		(pad "18" smd rect
			(at 2.456 1.3 90)
			(size 0.28 0.85)
			(layers "F.Cu" "F.Mask" "F.Paste")
			(net 449 "ULPI1_DATA6")
			(pinfunction "DATA[6]")
			(pintype "bidirectional")
			(solder_mask_margin 0.07)
		)
		(pad "19" smd rect
			(at 2.456 0.8 90)
			(size 0.28 0.85)
			(layers "F.Cu" "F.Mask" "F.Paste")
			(net 450 "ULPI1_DATA5")
			(pinfunction "DATA[5]")
			(pintype "bidirectional")
			(solder_mask_margin 0.07)
		)
		(pad "20" smd rect
			(at 2.456 0.296 90)
			(size 0.28 0.85)
			(layers "F.Cu" "F.Mask" "F.Paste")
			(net 451 "ULPI1_DATA4")
			(pinfunction "DATA[4]")
			(pintype "bidirectional")
			(solder_mask_margin 0.07)
		)
		(pad "21" smd rect
			(at 2.456 -0.201 90)
			(size 0.28 0.85)
			(layers "F.Cu" "F.Mask" "F.Paste")
			(net 452 "ULPI1_DATA3")
			(pinfunction "DATA[3]")
			(pintype "bidirectional")
			(solder_mask_margin 0.07)
		)
		(pad "22" smd rect
			(at 2.456 -0.701 90)
			(size 0.28 0.85)
			(layers "F.Cu" "F.Mask" "F.Paste")
			(net 453 "ULPI1_DATA2")
			(pinfunction "DATA[2]")
			(pintype "bidirectional")
			(solder_mask_margin 0.07)
		)
		(pad "23" smd rect
			(at 2.456 -1.2 90)
			(size 0.28 0.85)
			(layers "F.Cu" "F.Mask" "F.Paste")
			(net 454 "ULPI1_DATA1")
			(pinfunction "DATA[1]")
			(pintype "bidirectional")
			(solder_mask_margin 0.07)
		)
		(pad "24" smd rect
			(at 2.456 -1.702 90)
			(size 0.28 0.85)
			(layers "F.Cu" "F.Mask" "F.Paste")
			(net 455 "ULPI1_DATA0")
			(pinfunction "DATA[0]")
			(pintype "bidirectional")
			(solder_mask_margin 0.07)
		)
		(pad "25" smd rect
			(at 1.73 -2.426 90)
			(size 0.85 0.28)
			(layers "F.Cu" "F.Mask" "F.Paste")
			(net 2 "VCC3V3")
			(pinfunction "VDD3.3")
			(pintype "passive")
			(solder_mask_margin 0.07)
		)
		(pad "26" smd rect
			(at 1.23 -2.426 90)
			(size 0.85 0.28)
			(layers "F.Cu" "F.Mask" "F.Paste")
			(net 105 "Net-(C20-Pad2)")
			(pinfunction "VDD1.8")
			(pintype "passive")
			(solder_mask_margin 0.07)
		)
		(pad "27" smd rect
			(at 0.728 -2.426 90)
			(size 0.85 0.28)
			(layers "F.Cu" "F.Mask" "F.Paste")
			(net 650 "unconnected-(U17-XO-Pad27)")
			(pinfunction "XO")
			(pintype "output+no_connect")
			(solder_mask_margin 0.07)
		)
		(pad "28" smd rect
			(at 0.229 -2.426 90)
			(size 0.85 0.28)
			(layers "F.Cu" "F.Mask" "F.Paste")
			(net 651 "Net-(U17-XI)")
			(pinfunction "XI")
			(pintype "input")
			(solder_mask_margin 0.07)
		)
		(pad "29" smd rect
			(at -0.272 -2.426 90)
			(size 0.85 0.28)
			(layers "F.Cu" "F.Mask" "F.Paste")
			(net 12 "Net-(U17-VDDA1.8)")
			(pinfunction "VDDA1.8")
			(pintype "power_in")
			(solder_mask_margin 0.07)
		)
		(pad "30" smd rect
			(at -0.772 -2.426 90)
			(size 0.85 0.28)
			(layers "F.Cu" "F.Mask" "F.Paste")
			(net 2 "VCC3V3")
			(pinfunction "VDD3.3")
			(pintype "passive")
			(solder_mask_margin 0.07)
		)
		(pad "31" smd rect
			(at -1.269 -2.426 90)
			(size 0.85 0.28)
			(layers "F.Cu" "F.Mask" "F.Paste")
			(net 308 "Net-(U17-REG_EN)")
			(pinfunction "REG_EN")
			(pintype "bidirectional")
			(solder_mask_margin 0.07)
		)
		(pad "32" smd rect
			(at -1.768 -2.426 90)
			(size 0.85 0.28)
			(layers "F.Cu" "F.Mask" "F.Paste")
			(net 300 "Net-(U17-RBIAS)")
			(pinfunction "RBIAS")
			(pintype "bidirectional")
			(solder_mask_margin 0.07)
		)
		(pad "33" smd rect
			(at -0.02 0.048 90)
			(size 3.45 3.45)
			(layers "F.Cu" "F.Mask")
			(net 1 "GND")
			(pinfunction "EP")
			(pintype "passive")
		)
	)
)
